(kicad_pcb
	(version 20221018)
	(generator pcbnew)
	(general
    (thickness 1.656)
  )
	(paper "A4")
	(title_block
    (title "SDI-MIPI Bridge")
    (date "2023-08-09")
    (rev "1.3.4")
    (company "Antmicro")
		(comment 9 "footprints 165-174 of 190")
	)
	(layers
    (0 "F.Cu" signal)
    (1 "In1.Cu" power)
    (2 "In2.Cu" power)
    (3 "In3.Cu" signal)
    (4 "In4.Cu" signal)
    (31 "B.Cu" signal)
    (32 "B.Adhes" user "B.Adhesive")
    (33 "F.Adhes" user "F.Adhesive")
    (34 "B.Paste" user)
    (35 "F.Paste" user)
    (36 "B.SilkS" user "B.Silkscreen")
    (37 "F.SilkS" user "F.Silkscreen")
    (38 "B.Mask" user)
    (39 "F.Mask" user)
    (40 "Dwgs.User" user "User.Drawings")
    (41 "Cmts.User" user "User.Comments")
    (42 "Eco1.User" user "User.Eco1")
    (43 "Eco2.User" user "User.Eco2")
    (44 "Edge.Cuts" user)
    (45 "Margin" user)
    (46 "B.CrtYd" user "B.Courtyard")
    (47 "F.CrtYd" user "F.Courtyard")
    (48 "B.Fab" user)
    (49 "F.Fab" user)
  )
	(footprint "sdi-mipi-bridge-footprints:R_0402_1005Metric" (layer "B.Cu")
    (at 144.775 107.87 180)
    (descr "Resistor SMD 0402")
    (tags "resistor SMD 0402")
    (property "Author" "Antmicro")
    (property "Current" "1A")
    (property "DNP" "DNP")
    (property "License" "Apache-2.0")
    (property "MPN" "ERJ2GE0R00X")
    (property "Manufacturer" "Panasonic")
    (property "Sheetfile" "sdi-mipi-bridge.kicad_sch")
    (property "Sheetname" "")
    (property "Tolerance" "")
    (property "Val" "0R")
    (property "ki_description" "0R resistor in 0402 package with unspecified tolerance")
    (attr exclude_from_pos_files)
    (fp_text reference "R89" (at 0.975 -0.13) (layer "B.SilkS")
        (effects (font (size 0.7 0.7) (thickness 0.15)) (justify left bottom mirror))
    )
    (fp_text value "R_0R_0402" (at 0 -1.4) (layer "B.Fab") hide
        (effects (font (size 0.7 0.7) (thickness 0.15)) (justify left bottom mirror))
    )
    (fp_text user "License: Apache-2.0" (at -0.95 -5.169) (layer "B.Fab") hide
        (effects (font (size 0.7 0.7) (thickness 0.15)) (justify left bottom mirror))
    )
    (fp_text user "${REFERENCE}" (at -0.95 -3.168) (layer "B.Fab") hide
        (effects (font (size 0.7 0.7) (thickness 0.15)) (justify left bottom mirror))
    )
    (fp_text user "Author: Antmicro" (at -0.95 -4.169) (layer "B.Fab") hide
        (effects (font (size 0.7 0.7) (thickness 0.15)) (justify left bottom mirror))
    )
    (fp_rect (start -0.93 0.47) (end 0.93 -0.47)
      (stroke (width 0.05) (type solid)) (fill none) (layer "B.CrtYd"))
    (fp_rect (start -0.5 0.25) (end 0.5 -0.25)
      (stroke (width 0.15) (type solid)) (fill none) (layer "B.Fab"))
    (pad "1" smd roundrect (at -0.485 0 180) (size 0.59 0.64) (layers "B.Cu" "B.Paste" "B.Mask") (roundrect_rratio 0.25)
      (net 1 "GNDREF") (pintype "passive"))
    (pad "2" smd roundrect (at 0.485 0 180) (size 0.59 0.64) (layers "B.Cu" "B.Paste" "B.Mask") (roundrect_rratio 0.25)
      (net 100 "/CRESET_B") (pintype "passive"))
  )
	(footprint "sdi-mipi-bridge-footprints:C_0603_1608Metric" (layer "B.Cu")
    (at 128.7 133.253 90)
    (descr "Capacitor SMD 0603")
    (tags "capacitor 0603")
    (property "Author" "Antmicro")
    (property "License" "Apache-2.0")
    (property "MPN" "GRM188R61A106KE69D")
    (property "Manufacturer" "Murata")
    (property "Sheetfile" "sdi-mipi-bridge.kicad_sch")
    (property "Sheetname" "")
    (property "Val" "10u")
    (property "Voltage" "")
    (property "ki_description" " ")
    (attr smd)
    (fp_text reference "C1" (at 1.853 0.5 90) (layer "B.SilkS")
        (effects (font (size 0.7 0.7) (thickness 0.15)) (justify right bottom mirror))
    )
    (fp_text value "C_10u_0603" (at 0 -1.6 90) (layer "B.Fab") hide
        (effects (font (size 0.7 0.7) (thickness 0.15)) (justify right bottom mirror))
    )
    (fp_text user "${REFERENCE}" (at -1.682 -3.895 90) (layer "B.Fab") hide
        (effects (font (size 0.7 0.7) (thickness 0.15)) (justify right bottom mirror))
    )
    (fp_text user "Author: Antmicro" (at -1.682 -4.894 90) (layer "B.Fab") hide
        (effects (font (size 0.7 0.7) (thickness 0.15)) (justify right bottom mirror))
    )
    (fp_text user "License: Apache-2.0" (at -1.682 -5.895 90) (layer "B.Fab") hide
        (effects (font (size 0.7 0.7) (thickness 0.15)) (justify right bottom mirror))
    )
    (fp_line (start -0.3 -0.3) (end 0.3 -0.3)
      (stroke (width 0.15) (type solid)) (layer "B.SilkS"))
    (fp_line (start -0.3 0.3) (end 0.3 0.3)
      (stroke (width 0.15) (type solid)) (layer "B.SilkS"))
    (fp_rect (start -1.24 0.7) (end 1.24 -0.7)
      (stroke (width 0.05) (type solid)) (fill none) (layer "B.CrtYd"))
    (fp_rect (start -0.8 0.4) (end 0.8 -0.4)
      (stroke (width 0.15) (type solid)) (fill none) (layer "B.Fab"))
    (pad "1" smd roundrect (at -0.7 0 90) (size 0.6 0.8) (layers "B.Cu" "B.Paste" "B.Mask") (roundrect_rratio 0.2)
      (net 1 "GNDREF") (pintype "passive"))
    (pad "2" smd roundrect (at 0.7 0 90) (size 0.6 0.8) (layers "B.Cu" "B.Paste" "B.Mask") (roundrect_rratio 0.2)
      (net 6 "+3V3") (pintype "passive"))
  )
	(footprint "sdi-mipi-bridge-footprints:R_0402_1005Metric" (layer "B.Cu")
    (at 135.6 131.58 -90)
    (descr "Resistor SMD 0402")
    (tags "resistor SMD 0402")
    (property "Author" "Antmicro")
    (property "Current" "1A")
    (property "License" "Apache-2.0")
    (property "MPN" "ERJ2GE0R00X")
    (property "Manufacturer" "Panasonic")
    (property "Sheetfile" "sdi-mipi-bridge.kicad_sch")
    (property "Sheetname" "")
    (property "Tolerance" "")
    (property "Val" "0R")
    (property "ki_description" "0R resistor in 0402 package with unspecified tolerance")
    (attr smd)
    (fp_text reference "R23" (at -1.18 -3.6 90) (layer "B.SilkS")
        (effects (font (size 0.7 0.7) (thickness 0.15)) (justify left bottom mirror))
    )
    (fp_text value "R_0R_0402" (at 0 -1.4 90) (layer "B.Fab") hide
        (effects (font (size 0.7 0.7) (thickness 0.15)) (justify left bottom mirror))
    )
    (fp_text user "Author: Antmicro" (at -0.95 -4.169 90) (layer "B.Fab") hide
        (effects (font (size 0.7 0.7) (thickness 0.15)) (justify left bottom mirror))
    )
    (fp_text user "License: Apache-2.0" (at -0.95 -5.169 90) (layer "B.Fab") hide
        (effects (font (size 0.7 0.7) (thickness 0.15)) (justify left bottom mirror))
    )
    (fp_text user "${REFERENCE}" (at -0.95 -3.168 90) (layer "B.Fab") hide
        (effects (font (size 0.7 0.7) (thickness 0.15)) (justify left bottom mirror))
    )
    (fp_rect (start -0.93 0.47) (end 0.93 -0.47)
      (stroke (width 0.05) (type solid)) (fill none) (layer "B.CrtYd"))
    (fp_rect (start -0.5 0.25) (end 0.5 -0.25)
      (stroke (width 0.15) (type solid)) (fill none) (layer "B.Fab"))
    (pad "1" smd roundrect (at -0.485 0 270) (size 0.59 0.64) (layers "B.Cu" "B.Paste" "B.Mask") (roundrect_rratio 0.25)
      (net 2 "+1V2") (pintype "passive"))
    (pad "2" smd roundrect (at 0.485 0 270) (size 0.59 0.64) (layers "B.Cu" "B.Paste" "B.Mask") (roundrect_rratio 0.25)
      (net 4 "VPP") (pintype "passive"))
  )
	(footprint "sdi-mipi-bridge-footprints:C_0402_1005Metric" (layer "B.Cu")
    (at 145.335 118.275 180)
    (descr "Capacitor SMD 0402")
    (tags "capacitor SMD 0402")
    (property "Author" "Antmicro")
    (property "Dielectric" "")
    (property "License" "Apache-2.0")
    (property "MPN" "0402X104K6R3CT")
    (property "Manufacturer" "Walsin")
    (property "Sheetfile" "sdi-mipi-bridge.kicad_sch")
    (property "Sheetname" "")
    (property "Val" "100n")
    (property "Voltage" "")
    (property "ki_description" " ")
    (attr smd)
    (fp_text reference "C54" (at -9.865 -8.125) (layer "B.SilkS")
        (effects (font (size 0.7 0.7) (thickness 0.15)) (justify left bottom mirror))
    )
    (fp_text value "C_100n_6V3_0402" (at 0 -1.4) (layer "B.Fab") hide
        (effects (font (size 0.7 0.7) (thickness 0.15)) (justify left bottom mirror))
    )
    (fp_text user "${REFERENCE}" (at -0.932 -3.168) (layer "B.Fab") hide
        (effects (font (size 0.7 0.7) (thickness 0.15)) (justify left bottom mirror))
    )
    (fp_text user "License: Apache-2.0" (at -0.932 -5.17) (layer "B.Fab") hide
        (effects (font (size 0.7 0.7) (thickness 0.15)) (justify left bottom mirror))
    )
    (fp_text user "Author: Antmicro" (at -0.932 -4.17) (layer "B.Fab") hide
        (effects (font (size 0.7 0.7) (thickness 0.15)) (justify left bottom mirror))
    )
    (fp_rect (start -0.94 0.47) (end 0.94 -0.47)
      (stroke (width 0.05) (type solid)) (fill none) (layer "B.CrtYd"))
    (fp_rect (start -0.499 0.249) (end 0.499 -0.249)
      (stroke (width 0.15) (type solid)) (fill none) (layer "B.Fab"))
    (pad "1" smd roundrect (at -0.484 0 180) (size 0.59 0.64) (layers "B.Cu" "B.Paste" "B.Mask") (roundrect_rratio 0.25)
      (net 1 "GNDREF") (pintype "passive"))
    (pad "2" smd roundrect (at 0.484 0 180) (size 0.59 0.64) (layers "B.Cu" "B.Paste" "B.Mask") (roundrect_rratio 0.25)
      (net 79 "VCC_IO") (pintype "passive"))
  )
	(footprint "sdi-mipi-bridge-footprints:C_0402_1005Metric" (layer "B.Cu")
    (at 147.96 118.87 90)
    (descr "Capacitor SMD 0402")
    (tags "capacitor SMD 0402")
    (property "Author" "Antmicro")
    (property "Dielectric" "")
    (property "License" "Apache-2.0")
    (property "MPN" "GRM155R61A475MEAAD")
    (property "Manufacturer" "Murata")
    (property "Sheetfile" "sdi-mipi-bridge.kicad_sch")
    (property "Sheetname" "")
    (property "Val" "4u7")
    (property "Voltage" "")
    (property "ki_description" " ")
    (attr smd)
    (fp_text reference "C42" (at -8.93 9.24 90) (layer "B.SilkS")
        (effects (font (size 0.7 0.7) (thickness 0.15)) (justify right bottom mirror))
    )
    (fp_text value "C_4u7_0402" (at 0 -1.4 90) (layer "B.Fab") hide
        (effects (font (size 0.7 0.7) (thickness 0.15)) (justify right bottom mirror))
    )
    (fp_text user "Author: Antmicro" (at -0.932 -4.17 90) (layer "B.Fab") hide
        (effects (font (size 0.7 0.7) (thickness 0.15)) (justify right bottom mirror))
    )
    (fp_text user "License: Apache-2.0" (at -0.932 -5.17 90) (layer "B.Fab") hide
        (effects (font (size 0.7 0.7) (thickness 0.15)) (justify right bottom mirror))
    )
    (fp_text user "${REFERENCE}" (at -0.932 -3.168 90) (layer "B.Fab") hide
        (effects (font (size 0.7 0.7) (thickness 0.15)) (justify right bottom mirror))
    )
    (fp_rect (start -0.94 0.47) (end 0.94 -0.47)
      (stroke (width 0.05) (type solid)) (fill none) (layer "B.CrtYd"))
    (fp_rect (start -0.499 0.249) (end 0.499 -0.249)
      (stroke (width 0.15) (type solid)) (fill none) (layer "B.Fab"))
    (pad "1" smd roundrect (at -0.484 0 90) (size 0.59 0.64) (layers "B.Cu" "B.Paste" "B.Mask") (roundrect_rratio 0.25)
      (net 1 "GNDREF") (pintype "passive"))
    (pad "2" smd roundrect (at 0.484 0 90) (size 0.59 0.64) (layers "B.Cu" "B.Paste" "B.Mask") (roundrect_rratio 0.25)
      (net 2 "+1V2") (pintype "passive"))
  )
	(footprint "sdi-mipi-bridge-footprints:FB_0603_1608Metric" (layer "B.Cu")
    (at 143.875 112.95 180)
    (property "Author" "Antmicro")
    (property "License" "Apache-2.0")
    (property "MPN" "BLM18PG121SN1D")
    (property "Manufacturer" "Murata")
    (property "Sheetfile" "sdi-mipi-bridge.kicad_sch")
    (property "Sheetname" "")
    (property "ki_description" "Ferrite Beads WE-TMSB Suppression 240Ohm 200mA ")
    (property "ki_keywords" " Multilayer Suppression Beads ")
    (attr smd)
    (fp_text reference "FB1" (at -0.725 0.8) (layer "B.SilkS")
        (effects (font (size 0.7 0.7) (thickness 0.15)) (justify left bottom mirror))
    )
    (fp_text value "BLM18PG121SH1D" (at 0 -1.5) (layer "B.Fab") hide
        (effects (font (size 0.7 0.7) (thickness 0.15)) (justify left bottom mirror))
    )
    (fp_text user "License: Apache-2.0" (at -1.653 -5.9) (layer "B.Fab") hide
        (effects (font (size 0.7 0.7) (thickness 0.15)) (justify left bottom mirror))
    )
    (fp_text user "${REFERENCE}" (at -1.653 -4.6) (layer "B.Fab") hide
        (effects (font (size 0.7 0.7) (thickness 0.15)) (justify left bottom mirror))
    )
    (fp_text user "Author: Antmicro" (at -1.653 -3.162) (layer "B.Fab") hide
        (effects (font (size 0.7 0.7) (thickness 0.15)) (justify left bottom mirror))
    )
    (fp_line (start -0.196 -0.406) (end 0.193 -0.406)
      (stroke (width 0.15) (type solid)) (layer "B.SilkS"))
    (fp_line (start -0.196 0.408) (end 0.193 0.408)
      (stroke (width 0.15) (type solid)) (layer "B.SilkS"))
    (fp_rect (start -1.3 0.6) (end 1.3 -0.6)
      (stroke (width 0.05) (type solid)) (fill none) (layer "B.CrtYd"))
    (fp_line (start -0.803 -0.406) (end -0.803 0.408)
      (stroke (width 0.15) (type solid)) (layer "B.Fab"))
    (fp_line (start 0.8 -0.406) (end -0.803 -0.406)
      (stroke (width 0.15) (type solid)) (layer "B.Fab"))
    (fp_line (start 0.8 0.408) (end -0.803 0.408)
      (stroke (width 0.15) (type solid)) (layer "B.Fab"))
    (fp_line (start 0.8 0.408) (end 0.8 -0.406)
      (stroke (width 0.15) (type solid)) (layer "B.Fab"))
    (pad "1" smd roundrect (at -0.891 0 180) (size 0.762 1.09) (layers "B.Cu" "B.Paste" "B.Mask") (roundrect_rratio 0.15)
      (net 6 "+3V3") (pintype "passive"))
    (pad "2" smd roundrect (at 0.888 0 180) (size 0.762 1.09) (layers "B.Cu" "B.Paste" "B.Mask") (roundrect_rratio 0.15)
      (net 79 "VCC_IO") (pintype "passive"))
  )
	(footprint "sdi-mipi-bridge-footprints:C_0402_1005Metric" (layer "B.Cu")
    (at 121 113.4 90)
    (descr "Capacitor SMD 0402")
    (tags "capacitor SMD 0402")
    (property "Author" "Antmicro")
    (property "Dielectric" "X7R")
    (property "License" "Apache-2.0")
    (property "MPN" "GRM155R71H103KA88D")
    (property "Manufacturer" "Murata")
    (property "Sheetfile" "sdi-mipi-bridge.kicad_sch")
    (property "Sheetname" "")
    (property "Val" "10n")
    (property "Voltage" "50V")
    (property "ki_description" " ")
    (attr smd)
    (fp_text reference "C2" (at -0.8 -0.6 90) (layer "B.SilkS")
        (effects (font (size 0.7 0.7) (thickness 0.15)) (justify right bottom mirror))
    )
    (fp_text value "C_10n_0402" (at 0 -1.4 90) (layer "B.Fab") hide
        (effects (font (size 0.7 0.7) (thickness 0.15)) (justify right bottom mirror))
    )
    (fp_text user "Author: Antmicro" (at -0.932 -4.17 90) (layer "B.Fab") hide
        (effects (font (size 0.7 0.7) (thickness 0.15)) (justify right bottom mirror))
    )
    (fp_text user "License: Apache-2.0" (at -0.932 -5.17 90) (layer "B.Fab") hide
        (effects (font (size 0.7 0.7) (thickness 0.15)) (justify right bottom mirror))
    )
    (fp_text user "${REFERENCE}" (at -0.932 -3.168 90) (layer "B.Fab") hide
        (effects (font (size 0.7 0.7) (thickness 0.15)) (justify right bottom mirror))
    )
    (fp_rect (start -0.94 0.47) (end 0.94 -0.47)
      (stroke (width 0.05) (type solid)) (fill none) (layer "B.CrtYd"))
    (fp_rect (start -0.499 0.249) (end 0.499 -0.249)
      (stroke (width 0.15) (type solid)) (fill none) (layer "B.Fab"))
    (pad "1" smd roundrect (at -0.484 0 90) (size 0.59 0.64) (layers "B.Cu" "B.Paste" "B.Mask") (roundrect_rratio 0.25)
      (net 1 "GNDREF") (pintype "passive"))
    (pad "2" smd roundrect (at 0.484 0 90) (size 0.59 0.64) (layers "B.Cu" "B.Paste" "B.Mask") (roundrect_rratio 0.25)
      (net 2 "+1V2") (pintype "passive"))
  )
	(footprint "sdi-mipi-bridge-footprints:R_0402_1005Metric" (layer "B.Cu")
    (at 133.5 107.16)
    (descr "Resistor SMD 0402")
    (tags "resistor SMD 0402")
    (property "Author" "Antmicro")
    (property "License" "Apache-2.0")
    (property "MPN" "CR0402-FX-1000GLF")
    (property "Manufacturer" "Bourns")
    (property "Sheetfile" "sdi-mipi-bridge.kicad_sch")
    (property "Sheetname" "")
    (property "Tolerance" "1%")
    (property "Val" "100R")
    (property "ki_description" "100R resistor in 0402 package with 1% tolerance")
    (attr smd)
    (fp_text reference "R64" (at 1.1 1.44 180) (layer "B.SilkS")
        (effects (font (size 0.7 0.7) (thickness 0.15)) (justify left bottom mirror))
    )
    (fp_text value "R_100R_0402" (at 0 -1.4 180) (layer "B.Fab") hide
        (effects (font (size 0.7 0.7) (thickness 0.15)) (justify left bottom mirror))
    )
    (fp_text user "License: Apache-2.0" (at -0.95 -5.169 180) (layer "B.Fab") hide
        (effects (font (size 0.7 0.7) (thickness 0.15)) (justify left bottom mirror))
    )
    (fp_text user "${REFERENCE}" (at -0.95 -3.168 180) (layer "B.Fab") hide
        (effects (font (size 0.7 0.7) (thickness 0.15)) (justify left bottom mirror))
    )
    (fp_text user "Author: Antmicro" (at -0.95 -4.169 180) (layer "B.Fab") hide
        (effects (font (size 0.7 0.7) (thickness 0.15)) (justify left bottom mirror))
    )
    (fp_rect (start -0.93 0.47) (end 0.93 -0.47)
      (stroke (width 0.05) (type solid)) (fill none) (layer "B.CrtYd"))
    (fp_rect (start -0.5 0.25) (end 0.5 -0.25)
      (stroke (width 0.15) (type solid)) (fill none) (layer "B.Fab"))
    (pad "1" smd roundrect (at -0.485 0) (size 0.59 0.64) (layers "B.Cu" "B.Paste" "B.Mask") (roundrect_rratio 0.25)
      (net 95 "Net-(D5-Pad1)") (pintype "passive"))
    (pad "2" smd roundrect (at 0.485 0) (size 0.59 0.64) (layers "B.Cu" "B.Paste" "B.Mask") (roundrect_rratio 0.25)
      (net 22 "/~{DATA_ERROR}") (pintype "passive"))
  )
	(footprint "sdi-mipi-bridge-footprints:R_0402_1005Metric" (layer "B.Cu")
    (at 127.5 110.9 90)
    (descr "Resistor SMD 0402")
    (tags "resistor SMD 0402")
    (property "Author" "Antmicro")
    (property "DNP" "DNP")
    (property "License" "Apache-2.0")
    (property "MPN" "CR0402-FX-1002GLF")
    (property "Manufacturer" "Bourns")
    (property "Sheetfile" "sdi-mipi-bridge.kicad_sch")
    (property "Sheetname" "")
    (property "Tolerance" "1%")
    (property "Val" "10k")
    (property "ki_description" "10k resistor in 0402 package with 1% tolerance")
    (attr exclude_from_pos_files)
    (fp_text reference "R84" (at -3.1 0.3 90) (layer "B.SilkS")
        (effects (font (size 0.7 0.7) (thickness 0.15)) (justify right bottom mirror))
    )
    (fp_text value "R_10k_0402" (at 0 -1.4 90) (layer "B.Fab") hide
        (effects (font (size 0.7 0.7) (thickness 0.15)) (justify right bottom mirror))
    )
    (fp_text user "Author: Antmicro" (at -0.95 -4.169 90) (layer "B.Fab") hide
        (effects (font (size 0.7 0.7) (thickness 0.15)) (justify right bottom mirror))
    )
    (fp_text user "License: Apache-2.0" (at -0.95 -5.169 90) (layer "B.Fab") hide
        (effects (font (size 0.7 0.7) (thickness 0.15)) (justify right bottom mirror))
    )
    (fp_text user "${REFERENCE}" (at -0.95 -3.168 90) (layer "B.Fab") hide
        (effects (font (size 0.7 0.7) (thickness 0.15)) (justify right bottom mirror))
    )
    (fp_rect (start -0.93 0.47) (end 0.93 -0.47)
      (stroke (width 0.05) (type solid)) (fill none) (layer "B.CrtYd"))
    (fp_rect (start -0.5 0.25) (end 0.5 -0.25)
      (stroke (width 0.15) (type solid)) (fill none) (layer "B.Fab"))
    (pad "1" smd roundrect (at -0.485 0 90) (size 0.59 0.64) (layers "B.Cu" "B.Paste" "B.Mask") (roundrect_rratio 0.25)
      (net 126 "/~{RST_TRST}") (pintype "passive"))
    (pad "2" smd roundrect (at 0.485 0 90) (size 0.59 0.64) (layers "B.Cu" "B.Paste" "B.Mask") (roundrect_rratio 0.25)
      (net 76 "IO_VDD") (pintype "passive"))
  )
	(footprint "sdi-mipi-bridge-footprints:R_0402_1005Metric" (layer "B.Cu")
    (at 152.795 106.41)
    (descr "Resistor SMD 0402")
    (tags "resistor SMD 0402")
    (property "Author" "Antmicro")
    (property "DNP" "DNP")
    (property "License" "Apache-2.0")
    (property "MPN" "CR0402-FX-2201GLF")
    (property "Manufacturer" "Bourns")
    (property "Sheetfile" "sdi-mipi-bridge.kicad_sch")
    (property "Sheetname" "")
    (property "Tolerance" "1%")
    (property "Val" "2k2")
    (property "ki_description" "2k2 resistor in 0402 package with 1% tolerance")
    (attr exclude_from_pos_files)
    (fp_text reference "R85" (at 3.005 -4.81 180) (layer "B.SilkS")
        (effects (font (size 0.7 0.7) (thickness 0.15)) (justify left bottom mirror))
    )
    (fp_text value "R_2k2_0402" (at 0 -1.4 180) (layer "B.Fab") hide
        (effects (font (size 0.7 0.7) (thickness 0.15)) (justify left bottom mirror))
    )
    (fp_text user "Author: Antmicro" (at -0.95 -4.169 180) (layer "B.Fab") hide
        (effects (font (size 0.7 0.7) (thickness 0.15)) (justify left bottom mirror))
    )
    (fp_text user "License: Apache-2.0" (at -0.95 -5.169 180) (layer "B.Fab") hide
        (effects (font (size 0.7 0.7) (thickness 0.15)) (justify left bottom mirror))
    )
    (fp_text user "${REFERENCE}" (at -0.95 -3.168 180) (layer "B.Fab") hide
        (effects (font (size 0.7 0.7) (thickness 0.15)) (justify left bottom mirror))
    )
    (fp_rect (start -0.93 0.47) (end 0.93 -0.47)
      (stroke (width 0.05) (type solid)) (fill none) (layer "B.CrtYd"))
    (fp_rect (start -0.5 0.25) (end 0.5 -0.25)
      (stroke (width 0.15) (type solid)) (fill none) (layer "B.Fab"))
    (pad "1" smd roundrect (at -0.485 0) (size 0.59 0.64) (layers "B.Cu" "B.Paste" "B.Mask") (roundrect_rratio 0.25)
      (net 98 "Net-(R67-Pad2)") (pintype "passive"))
    (pad "2" smd roundrect (at 0.485 0) (size 0.59 0.64) (layers "B.Cu" "B.Paste" "B.Mask") (roundrect_rratio 0.25)
      (net 99 "/SPI_SS(SCL)") (pintype "passive"))
  )
)
